FILE_TYPE = MACRO_DRAWING;
SET COLOR_WIRE YELLOW;
SET COLOR_PROP ORANGE;
SET COLOR_DOT WHITE;
SET COLOR_ARC YELLOW;
SET COLOR_BODY GREEN;
SET COLOR_NOTE PURPLE;
SET PROP_DISPLAY VALUE;
SET PAGE_NUMBER P464;
FORCEADD OFFPAGE..1
(-6875 5400);
FORCEPROP 2 LAST $XR0 185 
J 0
(-7127 5400);
DISPLAY 0.638298 (-7127 5400);
PAINT MONO (-7127 5400);
FORCEPROP 2 LAST $XR1 186 
J 0
(-7247 5400);
DISPLAY 0.638298 (-7247 5400);
PAINT MONO (-7247 5400);
FORCEPROP 2 LAST CDS_LIB standard
J 0
(-6875 5400);
DISPLAY INVISIBLE (-6875 5400);
FORCEPROP 1 LAST OFFPAGE TRUE
J 0
(-6550 5275);
DISPLAY 0.872340 (-6550 5275);
DISPLAY INVISIBLE (-6550 5275);
FORCEPROP 1 LAST COMMENT_BODY TRUE
J 0
(-6750 5300);
DISPLAY 0.872340 (-6750 5300);
PAINT GREEN (-6750 5300);
DISPLAY INVISIBLE (-6750 5300);
FORCEPROP 2 LAST PATH I1
J 0
(-6825 5475);
DISPLAY 0.680851 (-6825 5475);
DISPLAY INVISIBLE (-6825 5475);
FORCEADD P1V0..1
(-4750 6175);
FORCEPROP 3 LASTPIN (-4750 6125) SIG_NAME P1V8_CPU1_RT_1D\g
J 0
(-4740 6135);
DISPLAY 0.659574 (-4740 6135);
PAINT MONO (-4740 6135);
DISPLAY INVISIBLE (-4740 6135);
FORCEPROP 1 LAST HDL_POWER P1V8_CPU1_RT_1D
J 1
(-4750 6225);
DISPLAY 0.489362 (-4750 6225);
PAINT SKYBLUE (-4750 6225);
FORCEPROP 2 LAST CDS_LIB pure_quanta_power
J 0
(-4750 6175);
DISPLAY INVISIBLE (-4750 6175);
FORCEPROP 1 LAST PATH I18
J 0
(-4700 6200);
DISPLAY 0.872340 (-4700 6200);
PAINT AQUA (-4700 6200);
DISPLAY INVISIBLE (-4700 6200);
FORCEADD Q_CAP..1
(-5000 5875);
FORCEPROP 1 LAST LOCATION C7504
J 0
(-4950 5975);
DISPLAY 0.787234 (-4950 5975);
PAINT SKYBLUE (-4950 5975);
FORCEPROP 0 LAST $SEC 1
J 0
(-4950 6025);
DISPLAY 0.680851 (-4950 6025);
PAINT MONO (-4950 6025);
DISPLAY INVISIBLE (-4950 6025);
FORCEPROP 0 LAST CDS_SEC 1
J 0
(-4950 6025);
DISPLAY 0.680851 (-4950 6025);
DISPLAY INVISIBLE (-4950 6025);
FORCEPROP 1 LASTPIN (-5000 5975) $PN 1
J 0
(-4990 5955);
DISPLAY 0.787234 (-4990 5955);
PAINT MONO (-4990 5955);
FORCEPROP 1 LASTPIN (-5000 5775) $PN 2
J 0
(-4990 5755);
DISPLAY 0.787234 (-4990 5755);
PAINT MONO (-4990 5755);
FORCEPROP 1 LAST PACK_TYPE C0201
J 0
(-4950 5725);
DISPLAY 0.510638 (-4950 5725);
FORCEPROP 1 LAST VALUE 0.1UF
J 0
(-4950 5925);
DISPLAY 0.510638 (-4950 5925);
FORCEPROP 1 LAST TOLERANCE 10%
J 0
(-4950 5825);
DISPLAY 0.510638 (-4950 5825);
FORCEPROP 1 LAST MATERIAL X7S
J 0
(-4950 5775);
DISPLAY 0.510638 (-4950 5775);
FORCEPROP 1 LAST VOLTAGE 10V
J 0
(-4950 5875);
DISPLAY 0.510638 (-4950 5875);
FORCEPROP 2 LAST CDS_LIB pure_quanta
J 0
(-5000 5875);
DISPLAY INVISIBLE (-5000 5875);
FORCEPROP 1 LAST PATH I19
J 0
(-4950 6025);
DISPLAY 0.978723 (-4950 6025);
PAINT WHITE (-4950 6025);
DISPLAY INVISIBLE (-4950 6025);
FORCEPROP 1 LAST PART_NUMBER CH4102K6E00
J 0
(-4950 5725);
DISPLAY 0.978723 (-4950 5725);
DISPLAY INVISIBLE (-4950 5725);
FORCEADD OFFPAGE..3
R 2
(-6850 5350);
FORCEPROP 2 LAST $XR0 185 
J 0
(-7130 5350);
DISPLAY 0.638298 (-7130 5350);
PAINT MONO (-7130 5350);
FORCEPROP 2 LAST $XR1 186 
J 0
(-7250 5350);
DISPLAY 0.638298 (-7250 5350);
PAINT MONO (-7250 5350);
FORCEPROP 2 LAST CDS_LIB standard
J 0
(-6850 5350);
DISPLAY INVISIBLE (-6850 5350);
FORCEPROP 1 LAST OFFPAGE TRUE
J 2
(-7175 5225);
DISPLAY 0.872340 (-7175 5225);
PAINT GREEN (-7175 5225);
DISPLAY INVISIBLE (-7175 5225);
FORCEPROP 1 LAST COMMENT_BODY TRUE
J 2
(-6800 5250);
DISPLAY 0.872340 (-6800 5250);
PAINT GREEN (-6800 5250);
DISPLAY INVISIBLE (-6800 5250);
FORCEPROP 2 LAST PATH I2
J 0
(-6800 5425);
DISPLAY 0.680851 (-6800 5425);
DISPLAY INVISIBLE (-6800 5425);
FORCEADD UNIVERSAL_GND..1
(-5000 5650);
FORCEPROP 3 LASTPIN (-5000 5700) SIG_NAME GND\g
J 0
(-4990 5710);
DISPLAY 0.659574 (-4990 5710);
PAINT MONO (-4990 5710);
DISPLAY INVISIBLE (-4990 5710);
FORCEPROP 2 LAST CDS_LIB pure_quanta_power
J 0
(-5000 5650);
DISPLAY INVISIBLE (-5000 5650);
FORCEPROP 1 LAST HDL_POWER GND
J 1
(-4975 5575);
DISPLAY 0.872340 (-4975 5575);
PAINT GREEN (-4975 5575);
DISPLAY INVISIBLE (-4975 5575);
FORCEPROP 1 LAST PATH I20
J 0
(-4925 5650);
DISPLAY 0.872340 (-4925 5650);
PAINT AQUA (-4925 5650);
DISPLAY INVISIBLE (-4925 5650);
FORCEADD UNIVERSAL_GND..1
R 7
(-4700 5450);
FORCEPROP 3 LASTPIN (-4650 5450) SIG_NAME GND\g
J 0
(-4640 5460);
DISPLAY 0.659574 (-4640 5460);
PAINT MONO (-4640 5460);
DISPLAY INVISIBLE (-4640 5460);
FORCEPROP 2 LAST CDS_LIB pure_quanta_power
J 0
(-4700 5450);
DISPLAY INVISIBLE (-4700 5450);
FORCEPROP 1 LAST HDL_POWER GND
R 1
J 1
(-4775 5475);
DISPLAY 0.872340 (-4775 5475);
PAINT GREEN (-4775 5475);
DISPLAY INVISIBLE (-4775 5475);
FORCEPROP 1 LAST PATH I21
R 1
J 0
(-4700 5525);
DISPLAY 0.872340 (-4700 5525);
PAINT AQUA (-4700 5525);
DISPLAY INVISIBLE (-4700 5525);
FORCEADD Q_RES..2
(-3250 5250);
FORCEPROP 1 LAST LOCATION R6791
J 0
(-3205 5375);
DISPLAY 0.978723 (-3205 5375);
FORCEPROP 0 LAST $SEC 1
J 0
(-3200 5425);
DISPLAY 0.680851 (-3200 5425);
PAINT MONO (-3200 5425);
DISPLAY INVISIBLE (-3200 5425);
FORCEPROP 0 LAST CDS_SEC 1
J 0
(-3200 5425);
DISPLAY 0.680851 (-3200 5425);
DISPLAY INVISIBLE (-3200 5425);
FORCEPROP 1 LASTPIN (-3250 5350) $PN 1
J 0
(-3245 5312);
DISPLAY 0.787234 (-3245 5312);
PAINT MONO (-3245 5312);
FORCEPROP 1 LASTPIN (-3250 5150) $PN 2
J 0
(-3245 5160);
DISPLAY 0.787234 (-3245 5160);
PAINT MONO (-3245 5160);
FORCEPROP 1 LAST PACK_TYPE 0201LF
J 0
(-3210 5075);
DISPLAY 0.978723 (-3210 5075);
FORCEPROP 1 LAST MATERIAL CHIP
J 0
(-3210 5175);
DISPLAY 0.978723 (-3210 5175);
FORCEPROP 1 LAST VALUE 1K
J 0
(-3205 5325);
DISPLAY 0.978723 (-3205 5325);
FORCEPROP 1 LAST TOLERANCE 1%
J 0
(-3205 5275);
DISPLAY 0.978723 (-3205 5275);
FORCEPROP 1 LAST WATTAGE 1/20W
J 0
(-3210 5225);
DISPLAY 0.978723 (-3210 5225);
FORCEPROP 2 LAST CDS_LIB pure_quanta
J 0
(-3250 5250);
DISPLAY INVISIBLE (-3250 5250);
FORCEPROP 1 LAST PATH I22
J 0
(-3200 5425);
DISPLAY 0.978723 (-3200 5425);
PAINT WHITE (-3200 5425);
DISPLAY INVISIBLE (-3200 5425);
FORCEPROP 1 LAST PART_NUMBER CS21001FE07
J 0
(-3210 5125);
DISPLAY 0.978723 (-3210 5125);
DISPLAY INVISIBLE (-3210 5125);
FORCEADD UNIVERSAL_GND..1
(-3250 4900);
FORCEPROP 3 LASTPIN (-3250 4950) SIG_NAME GND\g
J 0
(-3240 4960);
DISPLAY 0.659574 (-3240 4960);
PAINT MONO (-3240 4960);
DISPLAY INVISIBLE (-3240 4960);
FORCEPROP 2 LAST CDS_LIB pure_quanta_power
J 0
(-3250 4900);
DISPLAY INVISIBLE (-3250 4900);
FORCEPROP 1 LAST HDL_POWER GND
J 1
(-3225 4825);
DISPLAY 0.872340 (-3225 4825);
PAINT GREEN (-3225 4825);
DISPLAY INVISIBLE (-3225 4825);
FORCEPROP 1 LAST PATH I23
J 0
(-3175 4900);
DISPLAY 0.872340 (-3175 4900);
PAINT AQUA (-3175 4900);
DISPLAY INVISIBLE (-3175 4900);
FORCEADD UNIVERSAL_GND..1
(-3400 5175);
FORCEPROP 3 LASTPIN (-3400 5225) SIG_NAME GND\g
J 0
(-3390 5235);
DISPLAY 0.659574 (-3390 5235);
PAINT MONO (-3390 5235);
DISPLAY INVISIBLE (-3390 5235);
FORCEPROP 2 LAST CDS_LIB pure_quanta_power
J 0
(-3400 5175);
DISPLAY INVISIBLE (-3400 5175);
FORCEPROP 1 LAST HDL_POWER GND
J 1
(-3375 5100);
DISPLAY 0.872340 (-3375 5100);
PAINT GREEN (-3375 5100);
DISPLAY INVISIBLE (-3375 5100);
FORCEPROP 1 LAST PATH I24
J 0
(-3325 5175);
DISPLAY 0.872340 (-3325 5175);
PAINT AQUA (-3325 5175);
DISPLAY INVISIBLE (-3325 5175);
FORCEADD Q_RES..1
(-5650 5400);
FORCEPROP 1 LAST LOCATION R697
J 0
(-5875 5400);
DISPLAY 0.787234 (-5875 5400);
FORCEPROP 2 LAST SEC 1
J 0
(-5700 5600);
DISPLAY 0.680851 (-5700 5600);
PAINT MONO (-5700 5600);
DISPLAY INVISIBLE (-5700 5600);
FORCEPROP 1 LASTPIN (-5750 5400) $PN 1
J 0
(-5738 5412);
DISPLAY 0.787234 (-5738 5412);
PAINT MONO (-5738 5412);
FORCEPROP 1 LASTPIN (-5550 5400) $PN 2
J 0
(-5588 5412);
DISPLAY 0.787234 (-5588 5412);
PAINT MONO (-5588 5412);
FORCEPROP 1 LAST MATERIAL CHIP
J 0
(-5675 5450);
DISPLAY 0.787234 (-5675 5450);
FORCEPROP 1 LAST PACK_TYPE 0201LF
J 0
(-5500 5450);
DISPLAY 0.787234 (-5500 5450);
FORCEPROP 1 LAST TOLERANCE 5%
J 0
(-5750 5500);
DISPLAY 0.787234 (-5750 5500);
FORCEPROP 1 LAST VALUE 0
J 2
(-5825 5500);
DISPLAY 0.787234 (-5825 5500);
FORCEPROP 1 LAST WATTAGE 1/20W
J 2
(-5700 5450);
DISPLAY 0.787234 (-5700 5450);
FORCEPROP 2 LAST CDS_LIB pure_quanta
J 0
(-5650 5400);
DISPLAY INVISIBLE (-5650 5400);
FORCEPROP 2 LAST SEC_TYPE 0201LF
J 0
(-5700 5600);
DISPLAY 0.680851 (-5700 5600);
DISPLAY INVISIBLE (-5700 5600);
FORCEPROP 1 LAST PATH I25
J 0
(-5700 5550);
DISPLAY 0.978723 (-5700 5550);
PAINT WHITE (-5700 5550);
DISPLAY INVISIBLE (-5700 5550);
FORCEPROP 1 LAST PART_NUMBER CS00001JE10
J 0
(-5625 5500);
DISPLAY 0.787234 (-5625 5500);
DISPLAY INVISIBLE (-5625 5500);
FORCEADD Q_RES..1
(-5650 5350);
FORCEPROP 1 LAST LOCATION R698
J 0
(-5900 5350);
DISPLAY 0.978723 (-5900 5350);
FORCEPROP 0 LAST $SEC 1
J 0
(-5900 5400);
DISPLAY 0.680851 (-5900 5400);
PAINT MONO (-5900 5400);
DISPLAY INVISIBLE (-5900 5400);
FORCEPROP 0 LAST CDS_SEC 1
J 0
(-5900 5400);
DISPLAY 0.680851 (-5900 5400);
DISPLAY INVISIBLE (-5900 5400);
FORCEPROP 1 LASTPIN (-5750 5350) $PN 1
J 0
(-5738 5362);
DISPLAY 0.787234 (-5738 5362);
PAINT MONO (-5738 5362);
FORCEPROP 1 LASTPIN (-5550 5350) $PN 2
J 0
(-5588 5362);
DISPLAY 0.787234 (-5588 5362);
PAINT MONO (-5588 5362);
FORCEPROP 1 LAST VALUE 33.2
J 2
(-5375 5250);
DISPLAY 0.787234 (-5375 5250);
FORCEPROP 1 LAST TOLERANCE 1%
J 0
(-5650 5250);
DISPLAY 0.787234 (-5650 5250);
FORCEPROP 1 LAST PACK_TYPE 0201LF
J 0
(-5475 5300);
DISPLAY 0.638298 (-5475 5300);
FORCEPROP 1 LAST MATERIAL CHIP
J 0
(-5975 5300);
DISPLAY 0.638298 (-5975 5300);
FORCEPROP 1 LAST WATTAGE 1/20W
J 2
(-5700 5250);
DISPLAY 0.787234 (-5700 5250);
FORCEPROP 2 LAST CDS_LIB pure_quanta
J 0
(-5650 5350);
DISPLAY INVISIBLE (-5650 5350);
FORCEPROP 1 LAST PATH I4
J 0
(-5700 5500);
DISPLAY 0.978723 (-5700 5500);
PAINT WHITE (-5700 5500);
DISPLAY INVISIBLE (-5700 5500);
FORCEPROP 1 LAST PART_NUMBER CS03321FE09
J 0
(-5825 5300);
DISPLAY 0.638298 (-5825 5300);
DISPLAY INVISIBLE (-5825 5300);
FORCEADD M24M02DRMN6TP..1
(-4225 5425);
FORCEPROP 1 LAST LOCATION U21
J 0
(-4419 5765);
DISPLAY 0.723404 (-4419 5765);
PAINT GREEN (-4419 5765);
FORCEPROP 0 LAST $SEC 1
J 0
(-4400 5900);
DISPLAY 0.680851 (-4400 5900);
PAINT MONO (-4400 5900);
DISPLAY INVISIBLE (-4400 5900);
FORCEPROP 0 LAST CDS_SEC 1
J 0
(-4400 5900);
DISPLAY 0.680851 (-4400 5900);
DISPLAY INVISIBLE (-4400 5900);
FORCEPROP 0 LASTPIN (-3900 5500) $PN 1
J 0
(-3890 5510);
DISPLAY 0.680851 (-3890 5510);
PAINT MONO (-3890 5510);
FORCEPROP 0 LASTPIN (-3900 5450) $PN 2
J 0
(-3890 5460);
DISPLAY 0.680851 (-3890 5460);
PAINT MONO (-3890 5460);
FORCEPROP 0 LASTPIN (-3900 5400) $PN 3
J 0
(-3890 5410);
DISPLAY 0.680851 (-3890 5410);
PAINT MONO (-3890 5410);
FORCEPROP 0 LASTPIN (-4550 5400) $PN 6
J 2
(-4560 5410);
DISPLAY 0.680851 (-4560 5410);
PAINT MONO (-4560 5410);
FORCEPROP 0 LASTPIN (-4550 5350) $PN 5
J 2
(-4560 5360);
DISPLAY 0.680851 (-4560 5360);
PAINT MONO (-4560 5360);
FORCEPROP 0 LASTPIN (-4550 5500) $PN 8
J 2
(-4560 5510);
DISPLAY 0.680851 (-4560 5510);
PAINT MONO (-4560 5510);
FORCEPROP 0 LASTPIN (-3900 5350) $PN 4
J 0
(-3890 5360);
DISPLAY 0.680851 (-3890 5360);
PAINT MONO (-3890 5360);
FORCEPROP 0 LASTPIN (-4550 5450) $PN 7
J 2
(-4560 5460);
DISPLAY 0.680851 (-4560 5460);
PAINT MONO (-4560 5460);
FORCEPROP 1 LAST MATERIAL IC
J 0
(-4419 5557);
DISPLAY 0.723404 (-4419 5557);
PAINT GREEN (-4419 5557);
FORCEPROP 2 LAST PART_TYPE SMLF
J 0
(-4400 5850);
DISPLAY 0.680851 (-4400 5850);
FORCEPROP 2 LAST VALUE M24M02-DRMN6TP
J 0
(-4400 5800);
DISPLAY 0.680851 (-4400 5800);
FORCEPROP 1 LAST NEEDS_NO_SIZE TRUE
J 0
(-4050 5357);
DISPLAY 0.723404 (-4050 5357);
PAINT GREEN (-4050 5357);
DISPLAY INVISIBLE (-4050 5357);
FORCEPROP 1 LAST CDS_LMAN_SYM_OUTLINE -175,125,175,-125
J 0
(-4225 5425);
DISPLAY 0.468085 (-4225 5425);
PAINT GREEN (-4225 5425);
DISPLAY INVISIBLE (-4225 5425);
FORCEPROP 2 LAST CDS_LIB pure_quanta
J 0
(-4225 5425);
DISPLAY INVISIBLE (-4225 5425);
FORCEPROP 1 LAST PATH I5
J 0
(-4050 5300);
DISPLAY 0.723404 (-4050 5300);
PAINT GREEN (-4050 5300);
DISPLAY INVISIBLE (-4050 5300);
FORCEPROP 1 LAST PART_NUMBER AKE33Z00600
J 0
(-4419 5651);
DISPLAY 0.723404 (-4419 5651);
PAINT GREEN (-4419 5651);
DISPLAY INVISIBLE (-4419 5651);
FORCEADD QUANTA_TITLE_BLOCK_C..1
(0 0);
FORCEPROP 0 LAST CDS_CON_LAST_MODIFIED Thu Sep 14 16:13:01 2023
J 0
(-1885 15);
DISPLAY INVISIBLE (-1885 15);
FORCEPROP 1 LAST CUSTOM_TXT_CDS <CON_LAST_MODIFIED>
J 0
(-1885 15);
DISPLAY 0.978723 (-1885 15);
FORCEPROP 2 LAST CUSTOM_TXT_CDS <XR_PAGE_TITLE>
J 0
(-7890 5250);
DISPLAY 0.638298 (-7890 5250);
PAINT PINK (-7890 5250);
DISPLAY INVISIBLE (-7890 5250);
FORCEPROP 1 LAST CUSTOM_TXT_CDS <NAME_2>
J 0
(-3175 50);
FORCEPROP 1 LAST CUSTOM_TXT_CDS <NAME_1>
J 0
(-3175 175);
FORCEPROP 1 LAST CUSTOM_TXT_CDS <Q_NUMBER>
J 0
(-1403 103);
DISPLAY 1.212766 (-1403 103);
FORCEPROP 1 LAST CUSTOM_TXT_CDS <Q_PROJ>
J 0
(-2382 102);
DISPLAY 1.212766 (-2382 102);
FORCEPROP 1 LAST CUSTOM_TXT_CDS <Q_REV>
J 0
(-184 103);
DISPLAY 1.212766 (-184 103);
FORCEPROP 1 LAST CUSTOM_TXT_CDS <CON_PAGE_NUM> OF <CON_TOTAL_PAGES>
J 0
(-446 18);
DISPLAY 0.978723 (-446 18);
FORCEPROP 1 LAST Q_TITLE RETIMER_CPU1_P3(7)
J 0
(-9366 26);
DISPLAY 2.446809 (-9366 26);
PAINT GREEN (-9366 26);
FORCEPROP 2 LAST CDS_XR_PAGE_TITLE CR-356 : @T6G_MB_LIB.T6G(SCH_1):PAGE356
J 0
(-7890 5250);
DISPLAY 0.638298 (-7890 5250);
PAINT PINK (-7890 5250);
DISPLAY INVISIBLE (-7890 5250);
FORCEPROP 2 LAST PAGE_BORDER TRUE
J 0
(-7890 5250);
DISPLAY 0.638298 (-7890 5250);
PAINT PINK (-7890 5250);
DISPLAY INVISIBLE (-7890 5250);
FORCEPROP 1 LAST CDS_LMAN_SYM_OUTLINE -9475,6775,100,-125
J 0
(0 0);
DISPLAY 0.468085 (0 0);
PAINT GREEN (0 0);
DISPLAY INVISIBLE (0 0);
FORCEPROP 2 LAST CDS_LIB pure_quanta
J 0
(0 0);
DISPLAY INVISIBLE (0 0);
FORCEPROP 1 LAST Q_DEPT BU9
J 1
(-3763 49);
DISPLAY 1.957447 (-3763 49);
PAINT GREEN (-3763 49);
DISPLAY INVISIBLE (-3763 49);
FORCEPROP 1 LAST COMMENT_BODY TRUE
J 0
(12 -13);
DISPLAY 0.978723 (12 -13);
PAINT GREEN (12 -13);
DISPLAY INVISIBLE (12 -13);
WIRE 16 -1 (-5000 5775)(-5000 5700);
WIRE 16 -1 (-4550 5450)(-4650 5450);
WIRE 16 -1 (-3250 5150)(-3250 4950);
WIRE 16 -1 (-3900 5350)(-3400 5350);
WIRE 16 -1 (-3400 5350)(-3400 5225);
WIRE 16 -1 (-5750 5400)(-6825 5400);
FORCEPROP 2 LAST SIG_NAME SMB_RT_CPU1_P3_ROM_R_SCL
J 0
(-6710 5410);
DISPLAY 0.680851 (-6710 5410);
WIRE 16 -1 (-4550 5400)(-5550 5400);
FORCEPROP 2 LAST SIG_NAME SMB_RT_CPU1_P3_ROM_SCL
J 0
(-5435 5410);
DISPLAY 0.680851 (-5435 5410);
FORCEPROP 2 LASTPROP $XRERR UNIQUE?
J 0
(-5675 5410);
DISPLAY 0.638298 (-5675 5410);
PAINT MONO (-5675 5410);
DISPLAY INVISIBLE (-5675 5410);
WIRE 16 -1 (-5750 5350)(-6800 5350);
FORCEPROP 2 LAST SIG_NAME SMB_RT_CPU1_P3_ROM_R_SDA
J 0
(-6710 5360);
DISPLAY 0.680851 (-6710 5360);
WIRE 16 -1 (-4750 5500)(-4550 5500);
WIRE 16 -1 (-4750 6050)(-4750 5500);
WIRE 16 -1 (-5000 6050)(-4750 6050);
WIRE 16 -1 (-4750 6050)(-4750 6125);
WIRE 16 -1 (-5000 5975)(-5000 6050);
WIRE 16 -1 (-4550 5350)(-5550 5350);
FORCEPROP 2 LAST SIG_NAME SMB_RT_CPU1_P3_ROM_SDA
J 0
(-5435 5360);
DISPLAY 0.680851 (-5435 5360);
FORCEPROP 2 LASTPROP $XRERR UNIQUE?
J 0
(-5675 5360);
DISPLAY 0.638298 (-5675 5360);
PAINT MONO (-5675 5360);
DISPLAY INVISIBLE (-5675 5360);
WIRE 16 -1 (-3900 5400)(-3250 5400);
FORCEPROP 2 LAST SIG_NAME U21_E2
J 0
(-3660 5410);
DISPLAY 0.680851 (-3660 5410);
FORCEPROP 2 LASTPROP $XRERR UNIQUE?
J 0
(-3900 5410);
DISPLAY 0.638298 (-3900 5410);
PAINT MONO (-3900 5410);
DISPLAY INVISIBLE (-3900 5410);
WIRE 16 -1 (-3250 5400)(-3250 5350);
DOT 1 (-4750 6050);
FORCENOTE
RETIMER EEPRO ADDRESS: 0XA0 (8 BIT) / 0X50 (7 BIT)
(-7225 4850) 0;
DISPLAY LEFT (-7225 4850);
DISPLAY 1.595745 (-7225 4850);
QUIT
